# S9S_MB_2U (Grand Teton) — schematic netlist excerpt (pin names and nets, part order shuffled) for the footprints in the layout excerpt that follows; sources: Cadence DE-HDL packaged netlist, KiCad conversion of 03242023_DA0F0TMBIJ0_F0T_Motherboard_J_brd_V01_OCP.brd

PU173  MOSFET_N  BSS138K EMPTY  pkg SMLF  page 281
  DRAIN  = FM_HBM_VPP_SEL_CPU0_D
  GATE  = FM_HBM2_HBM3_VPP_SEL
  SOURCE  = SH_PVPP_HBM_CPU0_N

C1546  Q_CAP_DIFFBUS  DIFF BUS_0.22UF 6.3V 20% X6S  pkg C0201  page 177 : \1\ = P5E_CPU1_PE3_TX_C_DN<0> ; \2\ = P5E_CPU1_PE3_TX_DN<0>
R676  Q_RES  0 5% CHIP  pkg 0402LF  page 230 : A = I3C_SPD_DDREFGH_CPU1_LVC1_R_SCL ; B = I3C_SPD_DDREFGH_CPU1_LVC1_SCL

(kicad_pcb
	(version 20260206)
	(generator "pcbnew")
	(generator_version "10.0")
	(general
		(thickness 1.6)
		(legacy_teardrops no)
	)
	(paper "A4")
	(title_block
		(title "03242023_DA0F0TMBIJ0_F0T_Motherboard_J_brd_V01_OCP.brd")
		(comment 1 "Grand Teton / footprints 1646-1648 of 6105")
	)
	(layers
		(0 "F.Cu" signal "TOP")
		(4 "In1.Cu" signal "GND")
		(6 "In2.Cu" signal "IN1")
		(8 "In3.Cu" signal "GND1")
		(10 "In4.Cu" signal "IN2")
		(12 "In5.Cu" signal "GND2")
		(14 "In6.Cu" signal "IN3")
		(16 "In7.Cu" signal "GND3")
		(18 "In8.Cu" signal "VCC")
		(20 "In9.Cu" signal "VCC1")
		(22 "In10.Cu" signal "GND4")
		(24 "In11.Cu" signal "IN4")
		(26 "In12.Cu" signal "GND5")
		(28 "In13.Cu" signal "IN5")
		(30 "In14.Cu" signal "GND6")
		(32 "In15.Cu" signal "IN6")
		(34 "In16.Cu" signal "GND7")
		(2 "B.Cu" signal "BOTTOM")
		(9 "F.Adhes" user "F.Adhesive")
		(11 "B.Adhes" user "B.Adhesive")
		(13 "F.Paste" user "Package Geometry/Pastemask Top")
		(15 "B.Paste" user "Package Geometry/Pastemask Bottom")
		(5 "F.SilkS" user "Ref Des/Silkscreen Top")
		(7 "B.SilkS" user "Ref Des/Silkscreen Bottom")
		(1 "F.Mask" user "Board Geometry/Soldermask Top")
		(3 "B.Mask" user "Board Geometry/Soldermask Bottom")
		(17 "Dwgs.User" user "User.Drawings")
		(19 "Cmts.User" user "User.Comments")
		(21 "Eco1.User" user "User.Eco1")
		(23 "Eco2.User" user "User.Eco2")
		(25 "Edge.Cuts" user "Board Geometry/Outline")
		(27 "Margin" user)
		(31 "F.CrtYd" user "Package Geometry/Place Bound Top")
		(29 "B.CrtYd" user "Package Geometry/Place Bound Bottom")
		(35 "F.Fab" user "Ref Des/Assembly Top")
		(33 "B.Fab" user "Ref Des/Assembly Bottom")
	)
	(footprint ""
		(layer "F.Cu")
		(at 81.739486 -142.041372 180)
		(property "Reference" "R676"
			(at 0 0 180)
			(layer "F.SilkS")
			(hide yes)
			(effects
				(font
					(size 1.27 1.27)
				)
			)
		)
		(property "Value" ""
			(at 0 0 180)
			(layer "F.Fab")
			(effects
				(font
					(size 1.27 1.27)
				)
			)
		)
		(duplicate_pad_numbers_are_jumpers no)
		(fp_line
			(start 0.7874 0.4064)
			(end -0.7874 0.4064)
			(stroke
				(width 0.1524)
				(type default)
			)
			(layer "F.SilkS")
		)
		(fp_line
			(start 0.7874 -0.4064)
			(end 0.7874 0.4064)
			(stroke
				(width 0.1524)
				(type default)
			)
			(layer "F.SilkS")
		)
		(fp_line
			(start -0.7874 0.4064)
			(end -0.7874 -0.4064)
			(stroke
				(width 0.1524)
				(type default)
			)
			(layer "F.SilkS")
		)
		(fp_line
			(start -0.7874 -0.4064)
			(end 0.7874 -0.4064)
			(stroke
				(width 0.1524)
				(type default)
			)
			(layer "F.SilkS")
		)
		(fp_line
			(start 0.67945 0.3048)
			(end 0.120396 0.3048)
			(stroke
				(width 0.1)
				(type default)
			)
			(layer "F.Fab")
		)
		(fp_line
			(start 0.67945 -0.3048)
			(end 0.67945 0.3048)
			(stroke
				(width 0.1)
				(type default)
			)
			(layer "F.Fab")
		)
		(fp_line
			(start 0.12065 -0.2794)
			(end 0.12065 -0.3048)
			(stroke
				(width 0.1)
				(type default)
			)
			(layer "F.Fab")
		)
		(fp_line
			(start 0.12065 -0.3048)
			(end 0.67945 -0.3048)
			(stroke
				(width 0.1)
				(type default)
			)
			(layer "F.Fab")
		)
		(fp_line
			(start 0.120396 0.3048)
			(end 0.120396 0.2794)
			(stroke
				(width 0.1)
				(type default)
			)
			(layer "F.Fab")
		)
		(fp_line
			(start 0.120396 0.2794)
			(end -0.12065 0.2794)
			(stroke
				(width 0.1)
				(type default)
			)
			(layer "F.Fab")
		)
		(fp_line
			(start -0.12065 0.3048)
			(end -0.67945 0.3048)
			(stroke
				(width 0.1)
				(type default)
			)
			(layer "F.Fab")
		)
		(fp_line
			(start -0.12065 0.2794)
			(end -0.12065 0.3048)
			(stroke
				(width 0.1)
				(type default)
			)
			(layer "F.Fab")
		)
		(fp_line
			(start -0.12065 -0.2794)
			(end 0.12065 -0.2794)
			(stroke
				(width 0.1)
				(type default)
			)
			(layer "F.Fab")
		)
		(fp_line
			(start -0.12065 -0.305054)
			(end -0.12065 -0.2794)
			(stroke
				(width 0.1)
				(type default)
			)
			(layer "F.Fab")
		)
		(fp_line
			(start -0.67945 0.3048)
			(end -0.67945 -0.305054)
			(stroke
				(width 0.1)
				(type default)
			)
			(layer "F.Fab")
		)
		(fp_line
			(start -0.67945 -0.305054)
			(end -0.12065 -0.305054)
			(stroke
				(width 0.1)
				(type default)
			)
			(layer "F.Fab")
		)
		(pad "1" smd circle
			(at -0.40005 0 180)
			(size 0 0)
			(layers "F.Cu" "F.Mask" "F.Paste")
			(net "I3C_SPD_DDREFGH_CPU1_LVC1_R_SCL")
		)
		(pad "2" smd circle
			(at 0.40005 0 180)
			(size 0 0)
			(layers "F.Cu" "F.Mask" "F.Paste")
			(net "I3C_SPD_DDREFGH_CPU1_LVC1_SCL")
		)
	)
	(footprint ""
		(layer "F.Cu")
		(at 366.644428 -362.786422 -90)
		(property "Reference" "PU173"
			(at -3.372866 0.046482 0)
			(unlocked yes)
			(layer "F.SilkS")
			(effects
				(font
					(size 0.7874 0.5842)
					(thickness 0.1524)
				)
			)
		)
		(property "Value" ""
			(at 0 0 270)
			(layer "F.Fab")
			(effects
				(font
					(size 1.27 1.27)
				)
			)
		)
		(duplicate_pad_numbers_are_jumpers no)
		(fp_line
			(start -1.949958 1.610106)
			(end -1.949958 -1.610106)
			(stroke
				(width 0.1524)
				(type default)
			)
			(layer "F.SilkS")
		)
		(fp_line
			(start 1.105662 1.610106)
			(end -1.949958 1.610106)
			(stroke
				(width 0.1524)
				(type default)
			)
			(layer "F.SilkS")
		)
		(fp_line
			(start 1.949958 -1.560068)
			(end 1.949958 0.953008)
			(stroke
				(width 0.1524)
				(type default)
			)
			(layer "F.SilkS")
		)
		(fp_line
			(start -1.949958 -1.610106)
			(end 1.949958 -1.610106)
			(stroke
				(width 0.1524)
				(type default)
			)
			(layer "F.SilkS")
		)
		(fp_line
			(start -0.750062 1.560068)
			(end -0.750062 -1.560068)
			(stroke
				(width 0.1)
				(type default)
			)
			(layer "F.Fab")
		)
		(fp_line
			(start 0.750062 1.560068)
			(end -0.750062 1.560068)
			(stroke
				(width 0.1)
				(type default)
			)
			(layer "F.Fab")
		)
		(fp_line
			(start -0.750062 -1.560068)
			(end 0.750062 -1.560068)
			(stroke
				(width 0.1)
				(type default)
			)
			(layer "F.Fab")
		)
		(fp_line
			(start 0.750062 -1.560068)
			(end 0.750062 1.560068)
			(stroke
				(width 0.1)
				(type default)
			)
			(layer "F.Fab")
		)
		(pad "D" smd rect
			(at 1.100074 0 180)
			(size 1.016 1.4224)
			(layers "F.Cu" "F.Mask" "F.Paste")
			(net "FM_HBM_VPP_SEL_CPU0_D")
		)
		(pad "G" smd rect
			(at -1.100074 -0.94996 180)
			(size 1.016 1.4224)
			(layers "F.Cu" "F.Mask" "F.Paste")
			(net "FM_HBM2_HBM3_VPP_SEL")
		)
		(pad "S" smd rect
			(at -1.100074 0.94996 180)
			(size 1.016 1.4224)
			(layers "F.Cu" "F.Mask" "F.Paste")
			(net "SH_PVPP_HBM_CPU0_N")
		)
	)
	(footprint ""
		(layer "F.Cu")
		(at 168.338754 -408.517344 -90)
		(property "Reference" "C1546"
			(at 0 0 270)
			(layer "F.SilkS")
			(hide yes)
			(effects
				(font
					(size 1.27 1.27)
				)
			)
		)
		(property "Value" ""
			(at 0 0 270)
			(layer "F.Fab")
			(effects
				(font
					(size 1.27 1.27)
				)
			)
		)
		(duplicate_pad_numbers_are_jumpers no)
		(fp_line
			(start -0.299974 0.150114)
			(end -0.299974 -0.150114)
			(stroke
				(width 0.1)
				(type default)
			)
			(layer "F.Fab")
		)
		(fp_line
			(start 0.299974 0.150114)
			(end -0.299974 0.150114)
			(stroke
				(width 0.1)
				(type default)
			)
			(layer "F.Fab")
		)
		(fp_line
			(start -0.299974 -0.150114)
			(end 0.299974 -0.150114)
			(stroke
				(width 0.1)
				(type default)
			)
			(layer "F.Fab")
		)
		(fp_line
			(start 0.299974 -0.150114)
			(end 0.299974 0.150114)
			(stroke
				(width 0.1)
				(type default)
			)
			(layer "F.Fab")
		)
		(pad "1" smd rect
			(at -0.2667 0 270)
			(size 0.3048 0.381)
			(layers "F.Cu" "F.Mask" "F.Paste")
			(net "P5E_CPU1_PE3_TX_C_DN<0>")
		)
		(pad "2" smd rect
			(at 0.2667 0 270)
			(size 0.3048 0.381)
			(layers "F.Cu" "F.Mask" "F.Paste")
			(net "P5E_CPU1_PE3_TX_DN<0>")
		)
	)
)
